(kicad_pcb
	(version 20260206)
	(generator "pcbnew")
	(generator_version "10.0")
	(general
		(thickness 1.6)
		(legacy_teardrops no)
	)
	(paper "A4")
	(title_block
		(title "Bryce Canyon_F.DPB_16315-1-OCP.brd")
		(comment 1 "Bryce Canyon / footprints 945-952 of 2223")
	)
	(layers
		(0 "F.Cu" signal "TOP")
		(4 "In1.Cu" signal "L2GND")
		(6 "In2.Cu" signal "L3")
		(8 "In3.Cu" signal "L4GND")
		(10 "In4.Cu" signal "L5")
		(12 "In5.Cu" signal "L6VCC")
		(14 "In6.Cu" signal "L7VCC")
		(16 "In7.Cu" signal "L8")
		(18 "In8.Cu" signal "L9GND")
		(20 "In9.Cu" signal "L10")
		(22 "In10.Cu" signal "L11GND")
		(2 "B.Cu" signal "BOTTOM")
		(9 "F.Adhes" user "F.Adhesive")
		(11 "B.Adhes" user "B.Adhesive")
		(13 "F.Paste" user "Package Geometry/Pastemask Top")
		(15 "B.Paste" user "Package Geometry/Pastemask Bottom")
		(5 "F.SilkS" user "Ref Des/Silkscreen Top")
		(7 "B.SilkS" user "Ref Des/Silkscreen Bottom")
		(1 "F.Mask" user "Board Geometry/Soldermask Top")
		(3 "B.Mask" user "Board Geometry/Soldermask Bottom")
		(17 "Dwgs.User" user "User.Drawings")
		(19 "Cmts.User" user "User.Comments")
		(21 "Eco1.User" user "User.Eco1")
		(23 "Eco2.User" user "User.Eco2")
		(25 "Edge.Cuts" user "Board Geometry/Outline")
		(27 "Margin" user)
		(31 "F.CrtYd" user "Package Geometry/Place Bound Top")
		(29 "B.CrtYd" user "Package Geometry/Place Bound Bottom")
		(35 "F.Fab" user "Ref Des/Assembly Top")
		(33 "B.Fab" user "Ref Des/Assembly Bottom")
	)
	(footprint ""
		(layer "F.Cu")
		(at 86.545166 -14.92123 90)
		(property "Reference" "C15"
			(at 0 0 90)
			(layer "F.SilkS")
			(hide yes)
			(effects
				(font
					(size 1.27 1.27)
				)
			)
		)
		(property "Value" "SCD1U16V2KX-3GP"
			(at 1.1811 -2.7051 90)
			(unlocked yes)
			(layer "F.Fab")
			(hide yes)
			(effects
				(font
					(size 1.016 1.016)
					(thickness 0.1524)
				)
			)
		)
		(property "Device Type" "C402H22"
			(at 1.1811 -4.2291 90)
			(unlocked yes)
			(layer "F.Fab")
			(hide yes)
			(effects
				(font
					(size 1.016 1.016)
					(thickness 0.1524)
				)
			)
		)
		(duplicate_pad_numbers_are_jumpers no)
		(fp_rect
			(start -0.4318 0.9525)
			(end 0.4318 -0.9525)
			(stroke
				(width 0)
				(type default)
			)
			(fill no)
			(layer "F.CrtYd")
		)
		(fp_rect
			(start -0.4318 0.9525)
			(end 0.4318 -0.9525)
			(stroke
				(width 0)
				(type default)
			)
			(fill no)
			(layer "F.Fab")
		)
		(pad "1" smd custom
			(at 0 -0.4445 90)
			(size 0.1524 0.1524)
			(layers "F.Cu" "F.Mask" "F.Paste")
			(net "P3V3_STBY_A")
			(options
				(clearance outline)
				(anchor circle)
			)
			(primitives
				(gr_poly
					(pts
						(arc
							(start 0.3048 -0.2032)
							(mid 0.275042 -0.275042)
							(end 0.2032 -0.3048)
						)
						(arc
							(start -0.2032 -0.3048)
							(mid -0.275042 -0.275042)
							(end -0.3048 -0.2032)
						)
						(arc
							(start -0.3048 0.2032)
							(mid -0.275042 0.275042)
							(end -0.2032 0.3048)
						)
						(arc
							(start 0.2032 0.3048)
							(mid 0.275042 0.275042)
							(end 0.3048 0.2032)
						)
					)
					(width 0)
					(fill yes)
				)
			)
		)
		(pad "2" smd custom
			(at 0 0.4445 90)
			(size 0.1524 0.1524)
			(layers "F.Cu" "F.Mask" "F.Paste")
			(net "GND")
			(options
				(clearance outline)
				(anchor circle)
			)
			(primitives
				(gr_poly
					(pts
						(arc
							(start 0.3048 -0.2032)
							(mid 0.275042 -0.275042)
							(end 0.2032 -0.3048)
						)
						(arc
							(start -0.2032 -0.3048)
							(mid -0.275042 -0.275042)
							(end -0.3048 -0.2032)
						)
						(arc
							(start -0.3048 0.2032)
							(mid -0.275042 0.275042)
							(end -0.2032 0.3048)
						)
						(arc
							(start 0.2032 0.3048)
							(mid 0.275042 0.275042)
							(end 0.3048 0.2032)
						)
					)
					(width 0)
					(fill yes)
				)
			)
		)
	)
	(footprint ""
		(layer "F.Cu")
		(at 140.915898 -179.683918 -90)
		(property "Reference" "C252"
			(at 0 0 270)
			(layer "F.SilkS")
			(hide yes)
			(effects
				(font
					(size 1.27 1.27)
				)
			)
		)
		(property "Value" "SC4D7U25V5KX-1-GP"
			(at -0.0762 -6.1214 270)
			(unlocked yes)
			(layer "F.Fab")
			(hide yes)
			(effects
				(font
					(size 1.016 1.016)
					(thickness 0.1524)
				)
			)
		)
		(property "Device Type" "C805H58"
			(at -0.0762 -8.1534 270)
			(unlocked yes)
			(layer "F.Fab")
			(hide yes)
			(effects
				(font
					(size 1.016 1.016)
					(thickness 0.1524)
				)
			)
		)
		(duplicate_pad_numbers_are_jumpers no)
		(fp_line
			(start 0.635 0)
			(end -0.635 0)
			(stroke
				(width 0.508)
				(type default)
			)
			(layer "F.SilkS")
		)
		(fp_rect
			(start -0.9652 1.778)
			(end 0.9652 -1.778)
			(stroke
				(width 0)
				(type default)
			)
			(fill no)
			(layer "F.CrtYd")
		)
		(fp_poly
			(pts
				(xy -0.9652 -1.778) (xy 0.9652 -1.778) (xy 0.9652 1.778) (xy -0.9652 1.778)
			)
			(stroke
				(width 0)
				(type default)
			)
			(fill no)
			(layer "F.Fab")
		)
		(pad "1" smd rect
			(at 0 -0.9652 270)
			(size 1.397 1.143)
			(layers "F.Cu" "F.Mask" "F.Paste")
			(net "P12V_HDD16")
		)
		(pad "2" smd rect
			(at 0 0.9652 270)
			(size 1.397 1.143)
			(layers "F.Cu" "F.Mask" "F.Paste")
			(net "GND")
		)
	)
	(footprint ""
		(layer "F.Cu")
		(at 130.447796 -177.143918 -90)
		(property "Reference" "R475"
			(at 0 0 270)
			(layer "F.SilkS")
			(hide yes)
			(effects
				(font
					(size 1.27 1.27)
				)
			)
		)
		(property "Value" "10KR2F-2-GP"
			(at 0.064008 -3.993896 270)
			(unlocked yes)
			(layer "F.Fab")
			(hide yes)
			(effects
				(font
					(size 1.016 1.016)
					(thickness 0.1524)
				)
			)
		)
		(property "Device Type" "R402H16"
			(at 0.064008 -5.517896 270)
			(unlocked yes)
			(layer "F.Fab")
			(hide yes)
			(effects
				(font
					(size 1.016 1.016)
					(thickness 0.1524)
				)
			)
		)
		(duplicate_pad_numbers_are_jumpers no)
		(fp_line
			(start -0.508 -0.9398)
			(end -0.508 0.9398)
			(stroke
				(width 0.1524)
				(type default)
			)
			(layer "F.SilkS")
		)
		(fp_line
			(start 0.508 -0.9398)
			(end -0.508 -0.9398)
			(stroke
				(width 0.1524)
				(type default)
			)
			(layer "F.SilkS")
		)
		(fp_rect
			(start -0.508 0.9398)
			(end 0.508 -0.9398)
			(stroke
				(width 0)
				(type default)
			)
			(fill no)
			(layer "F.CrtYd")
		)
		(fp_rect
			(start -0.508 0.9398)
			(end 0.508 -0.9398)
			(stroke
				(width 0)
				(type default)
			)
			(fill no)
			(layer "F.Fab")
		)
		(pad "1" smd custom
			(at 0 -0.4445 270)
			(size 0.1397 0.1397)
			(layers "F.Cu" "F.Mask" "F.Paste")
			(net "P3V3_STBY_A")
			(options
				(clearance outline)
				(anchor circle)
			)
			(primitives
				(gr_poly
					(pts
						(arc
							(start -0.1778 -0.2794)
							(mid -0.249642 -0.249642)
							(end -0.2794 -0.1778)
						)
						(arc
							(start -0.2794 0.1778)
							(mid -0.249642 0.249642)
							(end -0.1778 0.2794)
						)
						(arc
							(start 0.1778 0.2794)
							(mid 0.249642 0.249642)
							(end 0.2794 0.1778)
						)
						(arc
							(start 0.2794 -0.1778)
							(mid 0.249642 -0.249642)
							(end 0.1778 -0.2794)
						)
					)
					(width 0)
					(fill yes)
				)
			)
		)
		(pad "2" smd custom
			(at 0 0.4445 270)
			(size 0.1397 0.1397)
			(layers "F.Cu" "F.Mask" "F.Paste")
			(net "HDD_PRSNT_15")
			(options
				(clearance outline)
				(anchor circle)
			)
			(primitives
				(gr_poly
					(pts
						(arc
							(start -0.1778 -0.2794)
							(mid -0.249642 -0.249642)
							(end -0.2794 -0.1778)
						)
						(arc
							(start -0.2794 0.1778)
							(mid -0.249642 0.249642)
							(end -0.1778 0.2794)
						)
						(arc
							(start 0.1778 0.2794)
							(mid 0.249642 0.249642)
							(end 0.2794 0.1778)
						)
						(arc
							(start 0.2794 -0.1778)
							(mid 0.249642 -0.249642)
							(end 0.1778 -0.2794)
						)
					)
					(width 0)
					(fill yes)
				)
			)
		)
	)
	(footprint ""
		(layer "F.Cu")
		(at 454.371202 -258.37515)
		(property "Reference" "TP258"
			(at 0 0 0)
			(layer "F.SilkS")
			(hide yes)
			(effects
				(font
					(size 1.27 1.27)
				)
			)
		)
		(property "Value" "TPAD32-GP"
			(at -0.0508 -1.6764 0)
			(unlocked yes)
			(layer "F.Fab")
			(hide yes)
			(effects
				(font
					(size 1.016 1.016)
					(thickness 0.1524)
				)
			)
		)
		(property "Device Type" "TPAD32"
			(at -0.0508 -3.2004 0)
			(unlocked yes)
			(layer "F.Fab")
			(hide yes)
			(effects
				(font
					(size 1.016 1.016)
					(thickness 0.1524)
				)
			)
		)
		(duplicate_pad_numbers_are_jumpers no)
		(fp_poly
			(pts
				(arc
					(start 0.4064 0)
					(mid -0.4064 0)
					(end 0.4064 0)
				)
			)
			(stroke
				(width 0)
				(type default)
			)
			(fill no)
			(layer "F.CrtYd")
		)
		(fp_poly
			(pts
				(arc
					(start 0.7112 0)
					(mid -0.7112 0)
					(end 0.7112 0)
				)
			)
			(stroke
				(width 0)
				(type default)
			)
			(fill no)
			(layer "F.Fab")
		)
		(pad "1" smd circle
			(at 0 0)
			(size 0.8128 0.8128)
			(layers "F.Cu" "F.Mask" "F.Paste")
			(net "P5V_A_3_PGOOD")
		)
	)
	(footprint ""
		(layer "F.Cu")
		(at 7.62 -304.292 180)
		(property "Reference" "R205"
			(at 0 0 180)
			(layer "F.SilkS")
			(hide yes)
			(effects
				(font
					(size 1.27 1.27)
				)
			)
		)
		(property "Value" "130R3F-GP"
			(at -0.0254 -2.5146 180)
			(unlocked yes)
			(layer "F.Fab")
			(hide yes)
			(effects
				(font
					(size 1.016 1.016)
					(thickness 0.1524)
				)
			)
		)
		(property "Device Type" "R603H22"
			(at -0.0254 -4.0386 180)
			(unlocked yes)
			(layer "F.Fab")
			(hide yes)
			(effects
				(font
					(size 1.016 1.016)
					(thickness 0.1524)
				)
			)
		)
		(duplicate_pad_numbers_are_jumpers no)
		(fp_line
			(start 0.2032 0)
			(end 0.4826 0)
			(stroke
				(width 0.2032)
				(type default)
			)
			(layer "F.SilkS")
		)
		(fp_line
			(start -0.4826 0)
			(end -0.2032 0)
			(stroke
				(width 0.2032)
				(type default)
			)
			(layer "F.SilkS")
		)
		(fp_rect
			(start -0.5842 1.3335)
			(end 0.5842 -1.3335)
			(stroke
				(width 0)
				(type default)
			)
			(fill no)
			(layer "F.CrtYd")
		)
		(fp_rect
			(start -0.5842 1.3335)
			(end 0.5842 -1.3335)
			(stroke
				(width 0)
				(type default)
			)
			(fill no)
			(layer "F.Fab")
		)
		(pad "1" smd custom
			(at 0 -0.762 180)
			(size 0.2159 0.2159)
			(layers "F.Cu" "F.Mask" "F.Paste")
			(net "P5V_B")
			(options
				(clearance outline)
				(anchor circle)
			)
			(primitives
				(gr_poly
					(pts
						(arc
							(start -0.3302 -0.4318)
							(mid -0.402042 -0.402042)
							(end -0.4318 -0.3302)
						)
						(arc
							(start -0.4318 0.3302)
							(mid -0.402042 0.402042)
							(end -0.3302 0.4318)
						)
						(arc
							(start 0.3302 0.4318)
							(mid 0.402042 0.402042)
							(end 0.4318 0.3302)
						)
						(arc
							(start 0.4318 -0.3302)
							(mid 0.402042 -0.402042)
							(end 0.3302 -0.4318)
						)
					)
					(width 0)
					(fill yes)
				)
			)
		)
		(pad "2" smd custom
			(at 0 0.762 180)
			(size 0.2159 0.2159)
			(layers "F.Cu" "F.Mask" "F.Paste")
			(net "FLT_HDD24")
			(options
				(clearance outline)
				(anchor circle)
			)
			(primitives
				(gr_poly
					(pts
						(arc
							(start -0.3302 -0.4318)
							(mid -0.402042 -0.402042)
							(end -0.4318 -0.3302)
						)
						(arc
							(start -0.4318 0.3302)
							(mid -0.402042 0.402042)
							(end -0.3302 0.4318)
						)
						(arc
							(start 0.3302 0.4318)
							(mid 0.402042 0.402042)
							(end 0.4318 0.3302)
						)
						(arc
							(start 0.4318 -0.3302)
							(mid 0.402042 -0.402042)
							(end 0.3302 -0.4318)
						)
					)
					(width 0)
					(fill yes)
				)
			)
		)
	)
	(footprint ""
		(layer "F.Cu")
		(at 138.653266 -143.898874 -90)
		(property "Reference" "R1041"
			(at 0 0 270)
			(layer "F.SilkS")
			(hide yes)
			(effects
				(font
					(size 1.27 1.27)
				)
			)
		)
		(property "Value" "0R2J-2-GP"
			(at 0.064008 -3.993896 270)
			(unlocked yes)
			(layer "F.Fab")
			(hide yes)
			(effects
				(font
					(size 1.016 1.016)
					(thickness 0.1524)
				)
			)
		)
		(property "Device Type" "R402H16"
			(at 0.064008 -5.517896 270)
			(unlocked yes)
			(layer "F.Fab")
			(hide yes)
			(effects
				(font
					(size 1.016 1.016)
					(thickness 0.1524)
				)
			)
		)
		(duplicate_pad_numbers_are_jumpers no)
		(fp_line
			(start -0.508 -0.9398)
			(end -0.508 0.9398)
			(stroke
				(width 0.1524)
				(type default)
			)
			(layer "F.SilkS")
		)
		(fp_line
			(start 0.508 -0.9398)
			(end -0.508 -0.9398)
			(stroke
				(width 0.1524)
				(type default)
			)
			(layer "F.SilkS")
		)
		(fp_rect
			(start -0.508 0.9398)
			(end 0.508 -0.9398)
			(stroke
				(width 0)
				(type default)
			)
			(fill no)
			(layer "F.CrtYd")
		)
		(fp_rect
			(start -0.508 0.9398)
			(end 0.508 -0.9398)
			(stroke
				(width 0)
				(type default)
			)
			(fill no)
			(layer "F.Fab")
		)
		(pad "1" smd custom
			(at 0 -0.4445 270)
			(size 0.1397 0.1397)
			(layers "F.Cu" "F.Mask" "F.Paste")
			(net "MB0_CM_ADR2_R")
			(options
				(clearance outline)
				(anchor circle)
			)
			(primitives
				(gr_poly
					(pts
						(arc
							(start -0.1778 -0.2794)
							(mid -0.249642 -0.249642)
							(end -0.2794 -0.1778)
						)
						(arc
							(start -0.2794 0.1778)
							(mid -0.249642 0.249642)
							(end -0.1778 0.2794)
						)
						(arc
							(start 0.1778 0.2794)
							(mid 0.249642 0.249642)
							(end 0.2794 0.1778)
						)
						(arc
							(start 0.2794 -0.1778)
							(mid 0.249642 -0.249642)
							(end 0.1778 -0.2794)
						)
					)
					(width 0)
					(fill yes)
				)
			)
		)
		(pad "2" smd custom
			(at 0 0.4445 270)
			(size 0.1397 0.1397)
			(layers "F.Cu" "F.Mask" "F.Paste")
			(net "AGND_CURRENT_MONOA")
			(options
				(clearance outline)
				(anchor circle)
			)
			(primitives
				(gr_poly
					(pts
						(arc
							(start -0.1778 -0.2794)
							(mid -0.249642 -0.249642)
							(end -0.2794 -0.1778)
						)
						(arc
							(start -0.2794 0.1778)
							(mid -0.249642 0.249642)
							(end -0.1778 0.2794)
						)
						(arc
							(start 0.1778 0.2794)
							(mid 0.249642 0.249642)
							(end 0.2794 0.1778)
						)
						(arc
							(start 0.2794 -0.1778)
							(mid 0.249642 -0.249642)
							(end 0.1778 -0.2794)
						)
					)
					(width 0)
					(fill yes)
				)
			)
		)
	)
	(footprint ""
		(layer "F.Cu")
		(at 469.898984 -279.098502 90)
		(property "Reference" "R399"
			(at 0 0 90)
			(layer "F.SilkS")
			(hide yes)
			(effects
				(font
					(size 1.27 1.27)
				)
			)
		)
		(property "Value" "200KR2F-L-GP"
			(at 0.064008 -3.993896 90)
			(unlocked yes)
			(layer "F.Fab")
			(hide yes)
			(effects
				(font
					(size 1.016 1.016)
					(thickness 0.1524)
				)
			)
		)
		(property "Device Type" "R402H16"
			(at 0.064008 -5.517896 90)
			(unlocked yes)
			(layer "F.Fab")
			(hide yes)
			(effects
				(font
					(size 1.016 1.016)
					(thickness 0.1524)
				)
			)
		)
		(duplicate_pad_numbers_are_jumpers no)
		(fp_line
			(start 0.508 -0.9398)
			(end -0.508 -0.9398)
			(stroke
				(width 0.1524)
				(type default)
			)
			(layer "F.SilkS")
		)
		(fp_line
			(start -0.508 -0.9398)
			(end -0.508 0.9398)
			(stroke
				(width 0.1524)
				(type default)
			)
			(layer "F.SilkS")
		)
		(fp_rect
			(start -0.508 0.9398)
			(end 0.508 -0.9398)
			(stroke
				(width 0)
				(type default)
			)
			(fill no)
			(layer "F.CrtYd")
		)
		(fp_rect
			(start -0.508 0.9398)
			(end 0.508 -0.9398)
			(stroke
				(width 0)
				(type default)
			)
			(fill no)
			(layer "F.Fab")
		)
		(pad "1" smd custom
			(at 0 -0.4445 90)
			(size 0.1397 0.1397)
			(layers "F.Cu" "F.Mask" "F.Paste")
			(net "SW_HDD_R11")
			(options
				(clearance outline)
				(anchor circle)
			)
			(primitives
				(gr_poly
					(pts
						(arc
							(start -0.1778 -0.2794)
							(mid -0.249642 -0.249642)
							(end -0.2794 -0.1778)
						)
						(arc
							(start -0.2794 0.1778)
							(mid -0.249642 0.249642)
							(end -0.1778 0.2794)
						)
						(arc
							(start 0.1778 0.2794)
							(mid 0.249642 0.249642)
							(end 0.2794 0.1778)
						)
						(arc
							(start 0.2794 -0.1778)
							(mid 0.249642 -0.249642)
							(end 0.1778 -0.2794)
						)
					)
					(width 0)
					(fill yes)
				)
			)
		)
		(pad "2" smd custom
			(at 0 0.4445 90)
			(size 0.1397 0.1397)
			(layers "F.Cu" "F.Mask" "F.Paste")
			(net "SW_HDD_N11")
			(options
				(clearance outline)
				(anchor circle)
			)
			(primitives
				(gr_poly
					(pts
						(arc
							(start -0.1778 -0.2794)
							(mid -0.249642 -0.249642)
							(end -0.2794 -0.1778)
						)
						(arc
							(start -0.2794 0.1778)
							(mid -0.249642 0.249642)
							(end -0.1778 0.2794)
						)
						(arc
							(start 0.1778 0.2794)
							(mid 0.249642 0.249642)
							(end 0.2794 0.1778)
						)
						(arc
							(start 0.2794 -0.1778)
							(mid 0.249642 -0.249642)
							(end 0.1778 -0.2794)
						)
					)
					(width 0)
					(fill yes)
				)
			)
		)
	)
	(footprint ""
		(layer "F.Cu")
		(at 69.620638 -188.85027)
		(property "Reference" "Q229"
			(at 0 0 0)
			(layer "F.SilkS")
			(hide yes)
			(effects
				(font
					(size 1.27 1.27)
				)
			)
		)
		(property "Value" "2N7002K-2-GP"
			(at 0.127 -8.9662 0)
			(unlocked yes)
			(layer "F.Fab")
			(hide yes)
			(effects
				(font
					(size 1.016 1.016)
					(thickness 0.1524)
				)
			)
		)
		(property "Device Type" "SOT23DGS2D4H44"
			(at 0.127 -10.4902 0)
			(unlocked yes)
			(layer "F.Fab")
			(hide yes)
			(effects
				(font
					(size 1.016 1.016)
					(thickness 0.1524)
				)
			)
		)
		(duplicate_pad_numbers_are_jumpers no)
		(fp_line
			(start -1.651 -1.778)
			(end -1.651 1.778)
			(stroke
				(width 0.1524)
				(type default)
			)
			(layer "F.SilkS")
		)
		(fp_line
			(start -1.651 1.778)
			(end 1.651 1.778)
			(stroke
				(width 0.1524)
				(type default)
			)
			(layer "F.SilkS")
		)
		(fp_line
			(start 1.651 -1.778)
			(end -1.651 -1.778)
			(stroke
				(width 0.1524)
				(type default)
			)
			(layer "F.SilkS")
		)
		(fp_line
			(start 1.651 1.778)
			(end 1.651 -1.778)
			(stroke
				(width 0.1524)
				(type default)
			)
			(layer "F.SilkS")
		)
		(fp_poly
			(pts
				(xy -1.778 1.8796) (xy -1.778 -1.8796) (xy 1.778 -1.8796) (xy 1.778 1.8796)
			)
			(stroke
				(width 0)
				(type default)
			)
			(fill no)
			(layer "F.CrtYd")
		)
		(fp_poly
			(pts
				(xy -1.778 1.8796) (xy -1.778 -1.8796) (xy 1.778 -1.8796) (xy 1.778 1.8796)
			)
			(stroke
				(width 0)
				(type default)
			)
			(fill no)
			(layer "F.Fab")
		)
		(pad "D" smd custom
			(at 0 -0.9525)
			(size 0.1905 0.1905)
			(layers "F.Cu" "F.Mask" "F.Paste")
			(net "FLT_HDD2_N")
			(options
				(clearance outline)
				(anchor circle)
			)
			(primitives
				(gr_poly
					(pts
						(arc
							(start -0.1778 0.5715)
							(mid -0.321484 0.511984)
							(end -0.381 0.3683)
						)
						(arc
							(start -0.381 -0.3683)
							(mid -0.321484 -0.511984)
							(end -0.1778 -0.5715)
						)
						(arc
							(start 0.1778 -0.5715)
							(mid 0.321484 -0.511984)
							(end 0.381 -0.3683)
						)
						(arc
							(start 0.381 0.3683)
							(mid 0.321484 0.511984)
							(end 0.1778 0.5715)
						)
					)
					(width 0)
					(fill yes)
				)
			)
		)
		(pad "G" smd custom
			(at -0.98425 0.9525)
			(size 0.1905 0.1905)
			(layers "F.Cu" "F.Mask" "F.Paste")
			(net "DRIVE_A_2_FLT_LED")
			(options
				(clearance outline)
				(anchor circle)
			)
			(primitives
				(gr_poly
					(pts
						(arc
							(start -0.1778 0.5715)
							(mid -0.321484 0.511984)
							(end -0.381 0.3683)
						)
						(arc
							(start -0.381 -0.3683)
							(mid -0.321484 -0.511984)
							(end -0.1778 -0.5715)
						)
						(arc
							(start 0.1778 -0.5715)
							(mid 0.321484 -0.511984)
							(end 0.381 -0.3683)
						)
						(arc
							(start 0.381 0.3683)
							(mid 0.321484 0.511984)
							(end 0.1778 0.5715)
						)
					)
					(width 0)
					(fill yes)
				)
			)
		)
		(pad "S" smd custom
			(at 0.98425 0.9525)
			(size 0.1905 0.1905)
			(layers "F.Cu" "F.Mask" "F.Paste")
			(net "GND")
			(options
				(clearance outline)
				(anchor circle)
			)
			(primitives
				(gr_poly
					(pts
						(arc
							(start -0.1778 0.5715)
							(mid -0.321484 0.511984)
							(end -0.381 0.3683)
						)
						(arc
							(start -0.381 -0.3683)
							(mid -0.321484 -0.511984)
							(end -0.1778 -0.5715)
						)
						(arc
							(start 0.1778 -0.5715)
							(mid 0.321484 -0.511984)
							(end 0.381 -0.3683)
						)
						(arc
							(start 0.381 0.3683)
							(mid 0.321484 0.511984)
							(end 0.1778 0.5715)
						)
					)
					(width 0)
					(fill yes)
				)
			)
		)
	)
)
